(kicad_pcb
	(version 20240108)
	(generator "pcbnew")
	(generator_version "8.0")
	(general
		(thickness 1.62)
		(legacy_teardrops no)
	)
	(paper "A4")
	(title_block
		(title "Jetson Orin Baseboard")
		(date "2025-03-12")
		(rev "1.3.4")
		(company "Antmicro Ltd")
		(comment 1 "www.antmicro.com")
		(comment 9 "footprints 281-285 of 677")
	)
	(layers
		(0 "F.Cu" signal)
		(1 "In1.Cu" signal)
		(2 "In2.Cu" signal)
		(3 "In3.Cu" signal)
		(4 "In4.Cu" jumper)
		(5 "In5.Cu" signal)
		(6 "In6.Cu" signal)
		(31 "B.Cu" signal)
		(32 "B.Adhes" user "B.Adhesive")
		(33 "F.Adhes" user "F.Adhesive")
		(34 "B.Paste" user)
		(35 "F.Paste" user)
		(36 "B.SilkS" user "B.Silkscreen")
		(37 "F.SilkS" user "F.Silkscreen")
		(38 "B.Mask" user)
		(39 "F.Mask" user)
		(40 "Dwgs.User" user "User.Drawings")
		(41 "Cmts.User" user "User.Comments")
		(42 "Eco1.User" user "User.Eco1")
		(43 "Eco2.User" user "User.Eco2")
		(44 "Edge.Cuts" user)
		(45 "Margin" user)
		(46 "B.CrtYd" user "B.Courtyard")
		(47 "F.CrtYd" user "F.Courtyard")
		(48 "B.Fab" user)
		(49 "F.Fab" user)
	)
	(footprint "antmicro-footprints:SOT-523"
		(layer "F.Cu")
		(at 85.4 113.15 90)
		(property "Reference" "Q12"
			(at 0.93 0.39 90)
			(layer "F.SilkS")
			(effects
				(font
					(size 0.7 0.7)
					(thickness 0.15)
				)
				(justify left bottom)
			)
		)
		(property "Value" "PJE138K"
			(at 0.1 1.824 90)
			(layer "F.Fab")
			(effects
				(font
					(size 0.7 0.7)
					(thickness 0.15)
				)
				(justify left bottom)
			)
		)
		(property "Footprint" "antmicro-footprints:SOT-523"
			(at 0 0 90)
			(layer "F.Fab")
			(hide yes)
			(effects
				(font
					(size 1.27 1.27)
					(thickness 0.15)
				)
			)
		)
		(property "Datasheet" "https://www.mouser.com/datasheet/2/1057/PJE138K-1876698.pdf"
			(at 0 0 90)
			(layer "F.Fab")
			(hide yes)
			(effects
				(font
					(size 1.27 1.27)
					(thickness 0.15)
				)
			)
		)
		(property "Author" "Antmicro"
			(at 198.55 27.75 0)
			(layer "F.Fab")
			(hide yes)
			(effects
				(font
					(size 1 1)
					(thickness 0.15)
				)
			)
		)
		(property "License" "Apache-2.0"
			(at 198.55 27.75 0)
			(layer "F.Fab")
			(hide yes)
			(effects
				(font
					(size 1 1)
					(thickness 0.15)
				)
			)
		)
		(property "MPN" "PJE138K_R1_00001"
			(at 198.55 27.75 0)
			(layer "F.Fab")
			(hide yes)
			(effects
				(font
					(size 1 1)
					(thickness 0.15)
				)
			)
		)
		(property "Manufacturer" "PANJIT"
			(at 198.55 27.75 0)
			(layer "F.Fab")
			(hide yes)
			(effects
				(font
					(size 1 1)
					(thickness 0.15)
				)
			)
		)
		(sheetname "HDMI")
		(sheetfile "hdmi.kicad_sch")
		(attr smd exclude_from_pos_files exclude_from_bom dnp)
		(fp_line
			(start -0.277 -0.551)
			(end -0.277 -0.75)
			(stroke
				(width 0.15)
				(type solid)
			)
			(layer "F.SilkS")
		)
		(fp_line
			(start -0.725 -0.551)
			(end -0.277 -0.551)
			(stroke
				(width 0.15)
				(type solid)
			)
			(layer "F.SilkS")
		)
		(fp_line
			(start -0.927 -0.351)
			(end -0.725 -0.551)
			(stroke
				(width 0.15)
				(type solid)
			)
			(layer "F.SilkS")
		)
		(fp_line
			(start -0.927 -0.051)
			(end -0.927 -0.351)
			(stroke
				(width 0.15)
				(type solid)
			)
			(layer "F.SilkS")
		)
		(fp_circle
			(center -0.9652 0.9652)
			(end -0.9152 0.9652)
			(stroke
				(width 0.15)
				(type solid)
			)
			(fill solid)
			(layer "F.SilkS")
		)
		(fp_line
			(start 1.1 -1.16)
			(end 1.1 1.15)
			(stroke
				(width 0.05)
				(type solid)
			)
			(layer "F.CrtYd")
		)
		(fp_line
			(start -1.12 -1.16)
			(end 1.1 -1.16)
			(stroke
				(width 0.05)
				(type solid)
			)
			(layer "F.CrtYd")
		)
		(fp_line
			(start -1.12 -1.16)
			(end -1.12 1.15)
			(stroke
				(width 0.05)
				(type solid)
			)
			(layer "F.CrtYd")
		)
		(fp_line
			(start -1.12 1.15)
			(end 1.1 1.15)
			(stroke
				(width 0.05)
				(type solid)
			)
			(layer "F.CrtYd")
		)
		(fp_line
			(start 0.8 -0.425)
			(end -0.652 -0.425)
			(stroke
				(width 0.15)
				(type solid)
			)
			(layer "F.Fab")
		)
		(fp_line
			(start 0.8 -0.425)
			(end 0.8 0.424)
			(stroke
				(width 0.15)
				(type solid)
			)
			(layer "F.Fab")
		)
		(fp_line
			(start -0.652 -0.425)
			(end -0.802 -0.276)
			(stroke
				(width 0.15)
				(type solid)
			)
			(layer "F.Fab")
		)
		(fp_line
			(start -0.802 -0.276)
			(end -0.802 0.424)
			(stroke
				(width 0.15)
				(type solid)
			)
			(layer "F.Fab")
		)
		(fp_line
			(start 0.8 0.424)
			(end -0.802 0.424)
			(stroke
				(width 0.15)
				(type solid)
			)
			(layer "F.Fab")
		)
		(fp_circle
			(center -0.9652 0.9652)
			(end -0.9144 0.9652)
			(stroke
				(width 0.15)
				(type solid)
			)
			(fill none)
			(layer "F.Fab")
		)
		(fp_text user "License: Apache-2.0"
			(at -1.12 5.024 90)
			(layer "F.Fab")
			(hide yes)
			(effects
				(font
					(size 0.7 0.7)
					(thickness 0.15)
				)
				(justify left bottom)
			)
		)
		(fp_text user "${REFERENCE}"
			(at -1.12 3.824 90)
			(layer "F.Fab")
			(hide yes)
			(effects
				(font
					(size 0.7 0.7)
					(thickness 0.15)
				)
				(justify left bottom)
			)
		)
		(fp_text user "Author: Antmicro"
			(at -1.12 6.224 90)
			(layer "F.Fab")
			(hide yes)
			(effects
				(font
					(size 0.7 0.7)
					(thickness 0.15)
				)
				(justify left bottom)
			)
		)
		(pad "1" smd rect
			(at -0.5 0.65 90)
			(size 0.4 0.51)
			(layers "F.Cu" "F.Paste" "F.Mask")
			(net 576 "/HDMI/HDMI_HPD_5V_R")
			(pinfunction "G")
			(pintype "passive")
		)
		(pad "2" smd rect
			(at 0.498 0.65 90)
			(size 0.4 0.51)
			(layers "F.Cu" "F.Paste" "F.Mask")
			(net 1 "GND")
			(pinfunction "S")
			(pintype "passive")
		)
		(pad "3" smd rect
			(at 0 -0.652 90)
			(size 0.4 0.51)
			(layers "F.Cu" "F.Paste" "F.Mask")
			(net 703 "/HDMI/HDMI_HPD")
			(pinfunction "D")
			(pintype "passive")
		)
	)
	(footprint "antmicro-footprints:R_0402_1005Metric"
		(layer "F.Cu")
		(at 148 109.5)
		(descr "Resistor SMD 0402")
		(tags "resistor SMD 0402")
		(property "Reference" "R121"
			(at -1.21 5.99 0)
			(layer "F.SilkS")
			(effects
				(font
					(size 0.7 0.7)
					(thickness 0.15)
				)
				(justify left bottom)
			)
		)
		(property "Value" "R_0R_0402"
			(at 0 1.4 0)
			(layer "F.Fab")
			(effects
				(font
					(size 0.7 0.7)
					(thickness 0.15)
				)
				(justify left bottom)
			)
		)
		(property "Footprint" "antmicro-footprints:R_0402_1005Metric"
			(at 0 0 0)
			(layer "F.Fab")
			(hide yes)
			(effects
				(font
					(size 1.27 1.27)
					(thickness 0.15)
				)
			)
		)
		(property "Datasheet" "https://industrial.panasonic.com/cdbs/www-data/pdf/RDA0000/AOA0000C301.pdf"
			(at 0 0 0)
			(layer "F.Fab")
			(hide yes)
			(effects
				(font
					(size 1.27 1.27)
					(thickness 0.15)
				)
			)
		)
		(property "Author" "Antmicro"
			(at 0 0 0)
			(layer "F.Fab")
			(hide yes)
			(effects
				(font
					(size 1 1)
					(thickness 0.15)
				)
			)
		)
		(property "Current" "1A"
			(at 0 0 0)
			(layer "F.Fab")
			(hide yes)
			(effects
				(font
					(size 1 1)
					(thickness 0.15)
				)
			)
		)
		(property "License" "Apache-2.0"
			(at 0 0 0)
			(layer "F.Fab")
			(hide yes)
			(effects
				(font
					(size 1 1)
					(thickness 0.15)
				)
			)
		)
		(property "MPN" "ERJ2GE0R00X"
			(at 0 0 0)
			(layer "F.Fab")
			(hide yes)
			(effects
				(font
					(size 1 1)
					(thickness 0.15)
				)
			)
		)
		(property "Manufacturer" "Panasonic"
			(at 0 0 0)
			(layer "F.Fab")
			(hide yes)
			(effects
				(font
					(size 1 1)
					(thickness 0.15)
				)
			)
		)
		(property "Tolerance" ""
			(at 0 0 0)
			(layer "F.Fab")
			(hide yes)
			(effects
				(font
					(size 1 1)
					(thickness 0.15)
				)
			)
		)
		(property "Val" "0R"
			(at 0 0 0)
			(layer "F.Fab")
			(hide yes)
			(effects
				(font
					(size 1 1)
					(thickness 0.15)
				)
			)
		)
		(sheetname "Peripherals")
		(sheetfile "peripherals.kicad_sch")
		(attr smd exclude_from_pos_files exclude_from_bom dnp)
		(fp_rect
			(start -0.925 -0.47)
			(end 0.925 0.47)
			(stroke
				(width 0.05)
				(type default)
			)
			(fill none)
			(layer "F.CrtYd")
		)
		(fp_rect
			(start -0.5 -0.25)
			(end 0.5 0.25)
			(stroke
				(width 0.15)
				(type solid)
			)
			(fill none)
			(layer "F.Fab")
		)
		(fp_text user "License: Apache-2.0"
			(at -0.95 5.169 0)
			(layer "F.Fab")
			(hide yes)
			(effects
				(font
					(size 0.7 0.7)
					(thickness 0.15)
				)
				(justify left bottom)
			)
		)
		(fp_text user "${REFERENCE}"
			(at -0.95 3.168 0)
			(layer "F.Fab")
			(hide yes)
			(effects
				(font
					(size 0.7 0.7)
					(thickness 0.15)
				)
				(justify left bottom)
			)
		)
		(fp_text user "Author: Antmicro"
			(at -0.95 4.169 0)
			(layer "F.Fab")
			(hide yes)
			(effects
				(font
					(size 0.7 0.7)
					(thickness 0.15)
				)
				(justify left bottom)
			)
		)
		(pad "1" smd roundrect
			(at -0.48 0)
			(size 0.59 0.64)
			(layers "F.Cu" "F.Paste" "F.Mask")
			(roundrect_rratio 0.25)
			(net 599 "Net-(J11-Pad66)")
			(pintype "passive")
		)
		(pad "2" smd roundrect
			(at 0.48 0)
			(size 0.59 0.64)
			(layers "F.Cu" "F.Paste" "F.Mask")
			(roundrect_rratio 0.25)
			(net 129 "I2C2_SCL")
			(pintype "passive")
		)
	)
	(footprint "antmicro-footprints:R_0402_1005Metric"
		(layer "F.Cu")
		(at 133.7 121.1 90)
		(descr "Resistor SMD 0402")
		(tags "resistor SMD 0402")
		(property "Reference" "R231"
			(at 0.75 0.45 90)
			(layer "F.SilkS")
			(effects
				(font
					(size 0.7 0.7)
					(thickness 0.15)
				)
				(justify left bottom)
			)
		)
		(property "Value" "R_200R_0402"
			(at 0 1.4 90)
			(layer "F.Fab")
			(effects
				(font
					(size 0.7 0.7)
					(thickness 0.15)
				)
				(justify left bottom)
			)
		)
		(property "Footprint" "antmicro-footprints:R_0402_1005Metric"
			(at 0 0 90)
			(layer "F.Fab")
			(hide yes)
			(effects
				(font
					(size 1.27 1.27)
					(thickness 0.15)
				)
			)
		)
		(property "Datasheet" "https://www.bourns.com/docs/product-datasheets/cr.pdf"
			(at 0 0 90)
			(layer "F.Fab")
			(hide yes)
			(effects
				(font
					(size 1.27 1.27)
					(thickness 0.15)
				)
			)
		)
		(property "Author" "Antmicro"
			(at 254.8 -12.6 0)
			(layer "F.Fab")
			(hide yes)
			(effects
				(font
					(size 1 1)
					(thickness 0.15)
				)
			)
		)
		(property "License" "Apache-2.0"
			(at 254.8 -12.6 0)
			(layer "F.Fab")
			(hide yes)
			(effects
				(font
					(size 1 1)
					(thickness 0.15)
				)
			)
		)
		(property "MPN" "CR0402-FX-2000GLF"
			(at 254.8 -12.6 0)
			(layer "F.Fab")
			(hide yes)
			(effects
				(font
					(size 1 1)
					(thickness 0.15)
				)
			)
		)
		(property "Manufacturer" "Bourns"
			(at 254.8 -12.6 0)
			(layer "F.Fab")
			(hide yes)
			(effects
				(font
					(size 1 1)
					(thickness 0.15)
				)
			)
		)
		(property "Tolerance" "1%"
			(at 254.8 -12.6 0)
			(layer "F.Fab")
			(hide yes)
			(effects
				(font
					(size 1 1)
					(thickness 0.15)
				)
			)
		)
		(property "Val" "200R"
			(at 254.8 -12.6 0)
			(layer "F.Fab")
			(hide yes)
			(effects
				(font
					(size 1 1)
					(thickness 0.15)
				)
			)
		)
		(sheetname "Peripherals")
		(sheetfile "peripherals.kicad_sch")
		(attr smd)
		(fp_rect
			(start -0.925 -0.47)
			(end 0.925 0.47)
			(stroke
				(width 0.05)
				(type default)
			)
			(fill none)
			(layer "F.CrtYd")
		)
		(fp_rect
			(start -0.5 -0.25)
			(end 0.5 0.25)
			(stroke
				(width 0.15)
				(type solid)
			)
			(fill none)
			(layer "F.Fab")
		)
		(fp_text user "${REFERENCE}"
			(at -0.95 3.168 90)
			(layer "F.Fab")
			(hide yes)
			(effects
				(font
					(size 0.7 0.7)
					(thickness 0.15)
				)
				(justify left bottom)
			)
		)
		(fp_text user "License: Apache-2.0"
			(at -0.95 5.169 90)
			(layer "F.Fab")
			(hide yes)
			(effects
				(font
					(size 0.7 0.7)
					(thickness 0.15)
				)
				(justify left bottom)
			)
		)
		(fp_text user "Author: Antmicro"
			(at -0.95 4.169 90)
			(layer "F.Fab")
			(hide yes)
			(effects
				(font
					(size 0.7 0.7)
					(thickness 0.15)
				)
				(justify left bottom)
			)
		)
		(pad "1" smd roundrect
			(at -0.48 0 90)
			(size 0.59 0.64)
			(layers "F.Cu" "F.Paste" "F.Mask")
			(roundrect_rratio 0.25)
			(net 182 "Net-(D27-A)")
			(pintype "passive")
		)
		(pad "2" smd roundrect
			(at 0.48 0 90)
			(size 0.59 0.64)
			(layers "F.Cu" "F.Paste" "F.Mask")
			(roundrect_rratio 0.25)
			(net 87 "+3V3")
			(pintype "passive")
		)
	)
	(footprint "antmicro-footprints:C_0402_1005Metric"
		(layer "F.Cu")
		(at 116.8 111.75 90)
		(descr "Capacitor SMD 0402")
		(tags "capacitor SMD 0402")
		(property "Reference" "C69"
			(at 0.8 0.35 90)
			(layer "F.SilkS")
			(effects
				(font
					(size 0.7 0.7)
					(thickness 0.15)
				)
				(justify left bottom)
			)
		)
		(property "Value" "C_100n_0402"
			(at 0 1.4 90)
			(layer "F.Fab")
			(effects
				(font
					(size 0.7 0.7)
					(thickness 0.15)
				)
				(justify left bottom)
			)
		)
		(property "Footprint" "antmicro-footprints:C_0402_1005Metric"
			(at 0 0 90)
			(layer "F.Fab")
			(hide yes)
			(effects
				(font
					(size 1.27 1.27)
					(thickness 0.15)
				)
			)
		)
		(property "Datasheet" "https://www.murata.com/products/productdetail?partno=GRM155R61H104KE14%23"
			(at 0 0 90)
			(layer "F.Fab")
			(hide yes)
			(effects
				(font
					(size 1.27 1.27)
					(thickness 0.15)
				)
			)
		)
		(property "Author" "Antmicro"
			(at 228.55 -5.05 0)
			(layer "F.Fab")
			(hide yes)
			(effects
				(font
					(size 1 1)
					(thickness 0.15)
				)
			)
		)
		(property "Dielectric" "X5R"
			(at 228.55 -5.05 0)
			(layer "F.Fab")
			(hide yes)
			(effects
				(font
					(size 1 1)
					(thickness 0.15)
				)
			)
		)
		(property "License" "Apache-2.0"
			(at 228.55 -5.05 0)
			(layer "F.Fab")
			(hide yes)
			(effects
				(font
					(size 1 1)
					(thickness 0.15)
				)
			)
		)
		(property "MPN" "GRM155R61H104KE14D"
			(at 228.55 -5.05 0)
			(layer "F.Fab")
			(hide yes)
			(effects
				(font
					(size 1 1)
					(thickness 0.15)
				)
			)
		)
		(property "Manufacturer" "Murata"
			(at 228.55 -5.05 0)
			(layer "F.Fab")
			(hide yes)
			(effects
				(font
					(size 1 1)
					(thickness 0.15)
				)
			)
		)
		(property "Val" "100n"
			(at 228.55 -5.05 0)
			(layer "F.Fab")
			(hide yes)
			(effects
				(font
					(size 1 1)
					(thickness 0.15)
				)
			)
		)
		(property "Voltage" "50V"
			(at 228.55 -5.05 0)
			(layer "F.Fab")
			(hide yes)
			(effects
				(font
					(size 1 1)
					(thickness 0.15)
				)
			)
		)
		(sheetname "USB3")
		(sheetfile "usb3.kicad_sch")
		(attr smd)
		(fp_rect
			(start -0.925 -0.47)
			(end 0.925 0.47)
			(stroke
				(width 0.05)
				(type default)
			)
			(fill none)
			(layer "F.CrtYd")
		)
		(fp_line
			(start 0.504 -0.25)
			(end 0.504 0.248)
			(stroke
				(width 0.15)
				(type solid)
			)
			(layer "F.Fab")
		)
		(fp_line
			(start -0.494 -0.25)
			(end 0.504 -0.25)
			(stroke
				(width 0.15)
				(type solid)
			)
			(layer "F.Fab")
		)
		(fp_line
			(start 0.504 0.248)
			(end -0.494 0.248)
			(stroke
				(width 0.15)
				(type solid)
			)
			(layer "F.Fab")
		)
		(fp_line
			(start -0.494 0.248)
			(end -0.494 -0.25)
			(stroke
				(width 0.15)
				(type solid)
			)
			(layer "F.Fab")
		)
		(fp_text user "Author: Antmicro"
			(at -0.932 4.17 90)
			(layer "F.Fab")
			(hide yes)
			(effects
				(font
					(size 0.7 0.7)
					(thickness 0.15)
				)
				(justify left bottom)
			)
		)
		(fp_text user "${REFERENCE}"
			(at -0.932 3.168 90)
			(layer "F.Fab")
			(hide yes)
			(effects
				(font
					(size 0.7 0.7)
					(thickness 0.15)
				)
				(justify left bottom)
			)
		)
		(fp_text user "License: Apache-2.0"
			(at -0.932 5.17 90)
			(layer "F.Fab")
			(hide yes)
			(effects
				(font
					(size 0.7 0.7)
					(thickness 0.15)
				)
				(justify left bottom)
			)
		)
		(pad "1" smd roundrect
			(at -0.48 0 90)
			(size 0.59 0.64)
			(layers "F.Cu" "F.Paste" "F.Mask")
			(roundrect_rratio 0.25)
			(net 263 "/USB3/USBC1_CONN_TX2_N")
			(pintype "passive")
		)
		(pad "2" smd roundrect
			(at 0.48 0 90)
			(size 0.59 0.64)
			(layers "F.Cu" "F.Paste" "F.Mask")
			(roundrect_rratio 0.25)
			(net 262 "/USB3/USBC1_TX2_N")
			(pintype "passive")
		)
	)
	(footprint "antmicro-footprints:R_0603_1608Metric"
		(layer "F.Cu")
		(at 137.2 111.8)
		(descr "Resistor SMD 0603")
		(tags "resistor SMD 0603")
		(property "Reference" "R234"
			(at -5.59 0.48 0)
			(layer "F.SilkS")
			(effects
				(font
					(size 0.7 0.7)
					(thickness 0.15)
				)
				(justify left bottom)
			)
		)
		(property "Value" "R_0R_0603"
			(at 0 1.6 0)
			(layer "F.Fab")
			(effects
				(font
					(size 0.7 0.7)
					(thickness 0.15)
				)
				(justify left bottom)
			)
		)
		(property "Footprint" "antmicro-footprints:R_0603_1608Metric"
			(at 0 0 0)
			(layer "F.Fab")
			(hide yes)
			(effects
				(font
					(size 1.27 1.27)
					(thickness 0.15)
				)
			)
		)
		(property "Datasheet" "https://www.bourns.com/docs/product-datasheets/cr.pdf?sfvrsn=574d41f6_14"
			(at 0 0 0)
			(layer "F.Fab")
			(hide yes)
			(effects
				(font
					(size 1.27 1.27)
					(thickness 0.15)
				)
			)
		)
		(property "Author" "Antmicro"
			(at 0 0 0)
			(layer "F.Fab")
			(hide yes)
			(effects
				(font
					(size 1 1)
					(thickness 0.15)
				)
			)
		)
		(property "Current" "1A"
			(at 0 0 0)
			(layer "F.Fab")
			(hide yes)
			(effects
				(font
					(size 1 1)
					(thickness 0.15)
				)
			)
		)
		(property "License" "Apache-2.0"
			(at 0 0 0)
			(layer "F.Fab")
			(hide yes)
			(effects
				(font
					(size 1 1)
					(thickness 0.15)
				)
			)
		)
		(property "MPN" "CR0603-J/-000ELF"
			(at 0 0 0)
			(layer "F.Fab")
			(hide yes)
			(effects
				(font
					(size 1 1)
					(thickness 0.15)
				)
			)
		)
		(property "Manufacturer" "Bourns"
			(at 0 0 0)
			(layer "F.Fab")
			(hide yes)
			(effects
				(font
					(size 1 1)
					(thickness 0.15)
				)
			)
		)
		(property "Tolerance" ""
			(at 0 0 0)
			(layer "F.Fab")
			(hide yes)
			(effects
				(font
					(size 1 1)
					(thickness 0.15)
				)
			)
		)
		(property "Val" "0R"
			(at 0 0 0)
			(layer "F.Fab")
			(hide yes)
			(effects
				(font
					(size 1 1)
					(thickness 0.15)
				)
			)
		)
		(sheetname "Peripherals")
		(sheetfile "peripherals.kicad_sch")
		(attr smd exclude_from_pos_files exclude_from_bom dnp)
		(fp_line
			(start -0.15 -0.4)
			(end 0.15 -0.4)
			(stroke
				(width 0.15)
				(type solid)
			)
			(layer "F.SilkS")
		)
		(fp_line
			(start -0.15 0.4)
			(end 0.15 0.4)
			(stroke
				(width 0.15)
				(type solid)
			)
			(layer "F.SilkS")
		)
		(fp_rect
			(start -1.25 -0.65)
			(end 1.25 0.65)
			(stroke
				(width 0.05)
				(type solid)
			)
			(fill none)
			(layer "F.CrtYd")
		)
		(fp_rect
			(start -0.8 -0.4)
			(end 0.8 0.4)
			(stroke
				(width 0.15)
				(type solid)
			)
			(fill none)
			(layer "F.Fab")
		)
		(fp_text user "License: Apache-2.0"
			(at -1.25 5.9 0)
			(layer "F.Fab")
			(hide yes)
			(effects
				(font
					(size 0.7 0.7)
					(thickness 0.15)
				)
				(justify left bottom)
			)
		)
		(fp_text user "Author: Antmicro"
			(at -1.25 4.9 0)
			(layer "F.Fab")
			(hide yes)
			(effects
				(font
					(size 0.7 0.7)
					(thickness 0.15)
				)
				(justify left bottom)
			)
		)
		(fp_text user "${REFERENCE}"
			(at -1.25 3.898 0)
			(layer "F.Fab")
			(hide yes)
			(effects
				(font
					(size 0.7 0.7)
					(thickness 0.15)
				)
				(justify left bottom)
			)
		)
		(pad "1" smd roundrect
			(at -0.7 0)
			(size 0.8 1)
			(layers "F.Cu" "F.Paste" "F.Mask")
			(roundrect_rratio 0.2)
			(net 112 "+1V8")
			(pintype "passive")
		)
		(pad "2" smd roundrect
			(at 0.7 0)
			(size 0.8 1)
			(layers "F.Cu" "F.Paste" "F.Mask")
			(roundrect_rratio 0.2)
			(net 483 "/Peripherals/1V8_CONN")
			(pintype "passive")
		)
	)
)
